# Lightning_FCB_SI constraints.xls — Net Rule by Layer (si-constraints)
| Project Name: 12433-2A |  |  |  |  |  |  |  |  |  |  |  |  |  |  |  |  |  |
| Project Path: C:\Users\<user>\Desktop\+-5%\12433-2A.DB |  |  |  |  |  |  |  |  |  |  |  |  |  |  |  |  |  |
| Net Name | Group Name | Type | Layer | T_W(X) | P-P | P-V | P-T | V-V | V-T | T_T(Y) | P-F | V-F | T-F | F-F | T_T(Z) | Ohm | Ref Layer |
| I2C_C_SCL | I2C | BUS | 1 | 5.5 | 5 | 10 | 5 | 12 | 5 | 15 | 12 | 12 | 12 | 12 |  |  |  |
| I2C_C_SCL_ADM1276 | I2C | BUS | 1 | 5.5 | 5 | 10 | 5 | 12 | 5 | 15 | 12 | 12 | 12 | 12 |  |  |  |
| I2C_C_SCL_CONN_R | I2C | BUS | 1 | 5.5 | 5 | 10 | 5 | 12 | 5 | 15 | 12 | 12 | 12 | 12 |  |  |  |
| I2C_C_SCL_EEPROM | I2C | BUS | 1 | 5.5 | 5 | 10 | 5 | 12 | 5 | 15 | 12 | 12 | 12 | 12 |  |  |  |
| I2C_C_SCL_LEDDRV | I2C | BUS | 1 | 5.5 | 5 | 10 | 5 | 12 | 5 | 15 | 12 | 12 | 12 | 12 |  |  |  |
| I2C_C_SCL_NCT7904 | I2C | BUS | 1 | 5.5 | 5 | 10 | 5 | 12 | 5 | 15 | 12 | 12 | 12 | 12 |  |  |  |
| I2C_C_SDA | I2C | BUS | 1 | 5.5 | 5 | 10 | 5 | 12 | 5 | 15 | 12 | 12 | 12 | 12 |  |  |  |
| I2C_C_SDA_ADM1276 | I2C | BUS | 1 | 5.5 | 5 | 10 | 5 | 12 | 5 | 15 | 12 | 12 | 12 | 12 |  |  |  |
| I2C_C_SDA_CONN_R | I2C | BUS | 1 | 5.5 | 5 | 10 | 5 | 12 | 5 | 15 | 12 | 12 | 12 | 12 |  |  |  |
| I2C_C_SDA_EEPROM | I2C | BUS | 1 | 5.5 | 5 | 10 | 5 | 12 | 5 | 15 | 12 | 12 | 12 | 12 |  |  |  |
| I2C_C_SDA_LEDDRV | I2C | BUS | 1 | 5.5 | 5 | 10 | 5 | 12 | 5 | 15 | 12 | 12 | 12 | 12 |  |  |  |
| I2C_C_SDA_NCT7904 | I2C | BUS | 1 | 5.5 | 5 | 10 | 5 | 12 | 5 | 15 | 12 | 12 | 12 | 12 |  |  |  |
| ADM1276_ADR | NORAML_BUS | BUS | 1 | 5.5 | 5 | 10 | 5 | 12 | 5 | 12 | 12 | 12 | 12 | 12 |  |  |  |
| ADM1276_GPIO2 | NORAML_BUS | BUS | 1 | 5.5 | 5 | 10 | 5 | 12 | 5 | 12 | 12 | 12 | 12 | 12 |  |  |  |
| D_LATCH_CLR | NORAML_BUS | BUS | 1 | 5.5 | 5 | 10 | 5 | 12 | 5 | 12 | 12 | 12 | 12 | 12 |  |  |  |
| D_LATCH_PRE# | NORAML_BUS | BUS | 1 | 5.5 | 5 | 10 | 5 | 12 | 5 | 12 | 12 | 12 | 12 | 12 |  |  |  |
| D_LATCH_Q | NORAML_BUS | BUS | 1 | 5.5 | 5 | 10 | 5 | 12 | 5 | 12 | 12 | 12 | 12 | 12 |  |  |  |
| D_LATCH_Q# | NORAML_BUS | BUS | 1 | 5.5 | 5 | 10 | 5 | 12 | 5 | 12 | 12 | 12 | 12 | 12 |  |  |  |
| EEPROM_WP | NORAML_BUS | BUS | 1 | 5.5 | 5 | 10 | 5 | 12 | 5 | 12 | 12 | 12 | 12 | 12 |  |  |  |
| FAN_TACH1 | NORAML_BUS | BUS | 1 | 5.5 | 5 | 10 | 5 | 12 | 5 | 12 | 12 | 12 | 12 | 12 |  |  |  |
| FAN_TACH10 | NORAML_BUS | BUS | 1 | 5.5 | 5 | 10 | 5 | 12 | 5 | 12 | 12 | 12 | 12 | 12 |  |  |  |
| FAN_TACH11 | NORAML_BUS | BUS | 1 | 5.5 | 5 | 10 | 5 | 12 | 5 | 12 | 12 | 12 | 12 | 12 |  |  |  |
| FAN_TACH12 | NORAML_BUS | BUS | 1 | 5.5 | 5 | 10 | 5 | 12 | 5 | 12 | 12 | 12 | 12 | 12 |  |  |  |
| FAN_TACH2 | NORAML_BUS | BUS | 1 | 5.5 | 5 | 10 | 5 | 12 | 5 | 12 | 12 | 12 | 12 | 12 |  |  |  |
| FAN_TACH3 | NORAML_BUS | BUS | 1 | 5.5 | 5 | 10 | 5 | 12 | 5 | 12 | 12 | 12 | 12 | 12 |  |  |  |
| FAN_TACH4 | NORAML_BUS | BUS | 1 | 5.5 | 5 | 10 | 5 | 12 | 5 | 12 | 12 | 12 | 12 | 12 |  |  |  |
| FAN_TACH5 | NORAML_BUS | BUS | 1 | 5.5 | 5 | 10 | 5 | 12 | 5 | 12 | 12 | 12 | 12 | 12 |  |  |  |
| FAN_TACH6 | NORAML_BUS | BUS | 1 | 5.5 | 5 | 10 | 5 | 12 | 5 | 12 | 12 | 12 | 12 | 12 |  |  |  |
| FAN_TACH7 | NORAML_BUS | BUS | 1 | 5.5 | 5 | 10 | 5 | 12 | 5 | 12 | 12 | 12 | 12 | 12 |  |  |  |
| FAN_TACH8 | NORAML_BUS | BUS | 1 | 5.5 | 5 | 10 | 5 | 12 | 5 | 12 | 12 | 12 | 12 | 12 |  |  |  |
| FAN_TACH9 | NORAML_BUS | BUS | 1 | 5.5 | 5 | 10 | 5 | 12 | 5 | 12 | 12 | 12 | 12 | 12 |  |  |  |
| FANIN_1 | NORAML_BUS | BUS | 1 | 5.5 | 5 | 10 | 5 | 12 | 5 | 12 | 12 | 12 | 12 | 12 |  |  |  |
| FANIN_10 | NORAML_BUS | BUS | 1 | 5.5 | 5 | 10 | 5 | 12 | 5 | 12 | 12 | 12 | 12 | 12 |  |  |  |
| FANIN_11 | NORAML_BUS | BUS | 1 | 5.5 | 5 | 10 | 5 | 12 | 5 | 12 | 12 | 12 | 12 | 12 |  |  |  |
| FANIN_12 | NORAML_BUS | BUS | 1 | 5.5 | 5 | 10 | 5 | 12 | 5 | 12 | 12 | 12 | 12 | 12 |  |  |  |
| FANIN_2 | NORAML_BUS | BUS | 1 | 5.5 | 5 | 10 | 5 | 12 | 5 | 12 | 12 | 12 | 12 | 12 |  |  |  |
| FANIN_3 | NORAML_BUS | BUS | 1 | 5.5 | 5 | 10 | 5 | 12 | 5 | 12 | 12 | 12 | 12 | 12 |  |  |  |
| FANIN_4 | NORAML_BUS | BUS | 1 | 5.5 | 5 | 10 | 5 | 12 | 5 | 12 | 12 | 12 | 12 | 12 |  |  |  |
| FANIN_5 | NORAML_BUS | BUS | 1 | 5.5 | 5 | 10 | 5 | 12 | 5 | 12 | 12 | 12 | 12 | 12 |  |  |  |
| FANIN_6 | NORAML_BUS | BUS | 1 | 5.5 | 5 | 10 | 5 | 12 | 5 | 12 | 12 | 12 | 12 | 12 |  |  |  |
| FANIN_7 | NORAML_BUS | BUS | 1 | 5.5 | 5 | 10 | 5 | 12 | 5 | 12 | 12 | 12 | 12 | 12 |  |  |  |
| FANIN_8 | NORAML_BUS | BUS | 1 | 5.5 | 5 | 10 | 5 | 12 | 5 | 12 | 12 | 12 | 12 | 12 |  |  |  |
| FANIN_9 | NORAML_BUS | BUS | 1 | 5.5 | 5 | 10 | 5 | 12 | 5 | 12 | 12 | 12 | 12 | 12 |  |  |  |
| FCB_EEPROM_A0 | NORAML_BUS | BUS | 1 | 5.5 | 5 | 10 | 5 | 12 | 5 | 12 | 12 | 12 | 12 | 12 |  |  |  |
| FCB_EEPROM_A1 | NORAML_BUS | BUS | 1 | 5.5 | 5 | 10 | 5 | 12 | 5 | 12 | 12 | 12 | 12 | 12 |  |  |  |
| FCB_EEPROM_A2 | NORAML_BUS | BUS | 1 | 5.5 | 5 | 10 | 5 | 12 | 5 | 12 | 12 | 12 | 12 | 12 |  |  |  |
| FCB_HW_REVISION | NORAML_BUS | BUS | 1 | 5.5 | 5 | 10 | 5 | 12 | 5 | 12 | 12 | 12 | 12 | 12 |  |  |  |
| LED_DR_LED0 | NORAML_BUS | BUS | 1 | 5.5 | 5 | 10 | 5 | 12 | 5 | 12 | 12 | 12 | 12 | 12 |  |  |  |
| LED_DR_LED0_B | NORAML_BUS | BUS | 1 | 5.5 | 5 | 10 | 5 | 12 | 5 | 12 | 12 | 12 | 12 | 12 |  |  |  |
| LED_DR_LED0_BLUE | NORAML_BUS | BUS | 1 | 5.5 | 5 | 10 | 5 | 12 | 5 | 12 | 12 | 12 | 12 | 12 |  |  |  |
| LED_DR_LED0_K | NORAML_BUS | BUS | 1 | 5.5 | 5 | 10 | 5 | 12 | 5 | 12 | 12 | 12 | 12 | 12 |  |  |  |
| LED_DR_LED1 | NORAML_BUS | BUS | 1 | 5.5 | 5 | 10 | 5 | 12 | 5 | 12 | 12 | 12 | 12 | 12 |  |  |  |
| LED_DR_LED1_B | NORAML_BUS | BUS | 1 | 5.5 | 5 | 10 | 5 | 12 | 5 | 12 | 12 | 12 | 12 | 12 |  |  |  |
| LED_DR_LED1_BLUE | NORAML_BUS | BUS | 1 | 5.5 | 5 | 10 | 5 | 12 | 5 | 12 | 12 | 12 | 12 | 12 |  |  |  |
| LED_DR_LED1_K | NORAML_BUS | BUS | 1 | 5.5 | 5 | 10 | 5 | 12 | 5 | 12 | 12 | 12 | 12 | 12 |  |  |  |
| LED_DR_LED2 | NORAML_BUS | BUS | 1 | 5.5 | 5 | 10 | 5 | 12 | 5 | 12 | 12 | 12 | 12 | 12 |  |  |  |
| LED_DR_LED2_B | NORAML_BUS | BUS | 1 | 5.5 | 5 | 10 | 5 | 12 | 5 | 12 | 12 | 12 | 12 | 12 |  |  |  |
| LED_DR_LED2_BLUE | NORAML_BUS | BUS | 1 | 5.5 | 5 | 10 | 5 | 12 | 5 | 12 | 12 | 12 | 12 | 12 |  |  |  |
| LED_DR_LED2_K | NORAML_BUS | BUS | 1 | 5.5 | 5 | 10 | 5 | 12 | 5 | 12 | 12 | 12 | 12 | 12 |  |  |  |
| LED_DR_LED3 | NORAML_BUS | BUS | 1 | 5.5 | 5 | 10 | 5 | 12 | 5 | 12 | 12 | 12 | 12 | 12 |  |  |  |
| LED_DR_LED3_B | NORAML_BUS | BUS | 1 | 5.5 | 5 | 10 | 5 | 12 | 5 | 12 | 12 | 12 | 12 | 12 |  |  |  |
| LED_DR_LED3_BLUE | NORAML_BUS | BUS | 1 | 5.5 | 5 | 10 | 5 | 12 | 5 | 12 | 12 | 12 | 12 | 12 |  |  |  |
| LED_DR_LED3_K | NORAML_BUS | BUS | 1 | 5.5 | 5 | 10 | 5 | 12 | 5 | 12 | 12 | 12 | 12 | 12 |  |  |  |
| LED_DR_LED4 | NORAML_BUS | BUS | 1 | 5.5 | 5 | 10 | 5 | 12 | 5 | 12 | 12 | 12 | 12 | 12 |  |  |  |
| LED_DR_LED4_B | NORAML_BUS | BUS | 1 | 5.5 | 5 | 10 | 5 | 12 | 5 | 12 | 12 | 12 | 12 | 12 |  |  |  |
| LED_DR_LED4_BLUE | NORAML_BUS | BUS | 1 | 5.5 | 5 | 10 | 5 | 12 | 5 | 12 | 12 | 12 | 12 | 12 |  |  |  |
| LED_DR_LED4_K | NORAML_BUS | BUS | 1 | 5.5 | 5 | 10 | 5 | 12 | 5 | 12 | 12 | 12 | 12 | 12 |  |  |  |
| LED_DR_LED5 | NORAML_BUS | BUS | 1 | 5.5 | 5 | 10 | 5 | 12 | 5 | 12 | 12 | 12 | 12 | 12 |  |  |  |
| LED_DR_LED5_B | NORAML_BUS | BUS | 1 | 5.5 | 5 | 10 | 5 | 12 | 5 | 12 | 12 | 12 | 12 | 12 |  |  |  |
| LED_DR_LED5_BLUE | NORAML_BUS | BUS | 1 | 5.5 | 5 | 10 | 5 | 12 | 5 | 12 | 12 | 12 | 12 | 12 |  |  |  |
| LED_DR_LED5_K | NORAML_BUS | BUS | 1 | 5.5 | 5 | 10 | 5 | 12 | 5 | 12 | 12 | 12 | 12 | 12 |  |  |  |
| LED_DR_LED6_RESERVE | NORAML_BUS | BUS | 1 | 5.5 | 5 | 10 | 5 | 12 | 5 | 12 | 12 | 12 | 12 | 12 |  |  |  |
| LED_DR_LED7_RESERVE | NORAML_BUS | BUS | 1 | 5.5 | 5 | 10 | 5 | 12 | 5 | 12 | 12 | 12 | 12 | 12 |  |  |  |
| LED_DRV_A0 | NORAML_BUS | BUS | 1 | 5.5 | 5 | 10 | 5 | 12 | 5 | 12 | 12 | 12 | 12 | 12 |  |  |  |
| LED_DRV_A1 | NORAML_BUS | BUS | 1 | 5.5 | 5 | 10 | 5 | 12 | 5 | 12 | 12 | 12 | 12 | 12 |  |  |  |
| LED_DRV_A2 | NORAML_BUS | BUS | 1 | 5.5 | 5 | 10 | 5 | 12 | 5 | 12 | 12 | 12 | 12 | 12 |  |  |  |
| LED_DRV_RST | NORAML_BUS | BUS | 1 | 5.5 | 5 | 10 | 5 | 12 | 5 | 12 | 12 | 12 | 12 | 12 |  |  |  |
| LOWER_TRAY_ID | NORAML_BUS | BUS | 1 | 5.5 | 5 | 10 | 5 | 12 | 5 | 12 | 12 | 12 | 12 | 12 |  |  |  |
| NCT7368S_SEL | NORAML_BUS | BUS | 1 | 5.5 | 5 | 10 | 5 | 12 | 5 | 12 | 12 | 12 | 12 | 12 |  |  |  |
| NCT7904_3VDD | NORAML_BUS | BUS | 1 | 5.5 | 5 | 10 | 5 | 12 | 5 | 12 | 12 | 12 | 12 | 12 |  |  |  |
| NCT7904_3VSB | NORAML_BUS | BUS | 1 | 5.5 | 5 | 10 | 5 | 12 | 5 | 12 | 12 | 12 | 12 | 12 |  |  |  |
| NCT7904_ADR | NORAML_BUS | BUS | 1 | 5.5 | 5 | 10 | 5 | 12 | 5 | 12 | 12 | 12 | 12 | 12 |  |  |  |
| NCT7904_CASEOPEN | NORAML_BUS | BUS | 1 | 5.5 | 5 | 10 | 5 | 12 | 5 | 12 | 12 | 12 | 12 | 12 |  |  |  |
| NCT7904_CLK | NORAML_BUS | BUS | 1 | 5.5 | 5 | 10 | 5 | 12 | 5 | 12 | 12 | 12 | 12 | 12 |  |  |  |
| NCT7904_CLKIN | NORAML_BUS | BUS | 1 | 5.5 | 5 | 10 | 5 | 12 | 5 | 12 | 12 | 12 | 12 | 12 |  |  |  |
| NCT7904_D1- | NORAML_BUS | BUS | 1 | 5.5 | 5 | 10 | 5 | 12 | 5 | 12 | 12 | 12 | 12 | 12 |  |  |  |
| NCT7904_D1+ | NORAML_BUS | BUS | 1 | 5.5 | 5 | 10 | 5 | 12 | 5 | 12 | 12 | 12 | 12 | 12 |  |  |  |
| NCT7904_D2- | NORAML_BUS | BUS | 1 | 5.5 | 5 | 10 | 5 | 12 | 5 | 12 | 12 | 12 | 12 | 12 |  |  |  |
| NCT7904_D2+ | NORAML_BUS | BUS | 1 | 5.5 | 5 | 10 | 5 | 12 | 5 | 12 | 12 | 12 | 12 | 12 |  |  |  |
| NCT7904_GND | NORAML_BUS | BUS | 1 | 5.5 | 5 | 10 | 5 | 12 | 5 | 12 | 12 | 12 | 12 | 12 |  |  |  |
| NCT7904_LED | NORAML_BUS | BUS | 1 | 5.5 | 5 | 10 | 5 | 12 | 5 | 12 | 12 | 12 | 12 | 12 |  |  |  |
| NCT7904_PECI | NORAML_BUS | BUS | 1 | 5.5 | 5 | 10 | 5 | 12 | 5 | 12 | 12 | 12 | 12 | 12 |  |  |  |
| NCT7904_PROCHOT | NORAML_BUS | BUS | 1 | 5.5 | 5 | 10 | 5 | 12 | 5 | 12 | 12 | 12 | 12 | 12 |  |  |  |
| NCT7904_RESET | NORAML_BUS | BUS | 1 | 5.5 | 5 | 10 | 5 | 12 | 5 | 12 | 12 | 12 | 12 | 12 |  |  |  |
| NCT7904_RSTOUT | NORAML_BUS | BUS | 1 | 5.5 | 5 | 10 | 5 | 12 | 5 | 12 | 12 | 12 | 12 | 12 |  |  |  |
| NCT7904_SMI | NORAML_BUS | BUS | 1 | 5.5 | 5 | 10 | 5 | 12 | 5 | 12 | 12 | 12 | 12 | 12 |  |  |  |
| NCT7904_THERMTRIP | NORAML_BUS | BUS | 1 | 5.5 | 5 | 10 | 5 | 12 | 5 | 12 | 12 | 12 | 12 | 12 |  |  |  |
| NCT7904_TMPALM | NORAML_BUS | BUS | 1 | 5.5 | 5 | 10 | 5 | 12 | 5 | 12 | 12 | 12 | 12 | 12 |  |  |  |
| NCT7904_VREF | NORAML_BUS | BUS | 1 | 5.5 | 5 | 10 | 5 | 12 | 5 | 12 | 12 | 12 | 12 | 12 |  |  |  |
| NCT7904_VSEN_P12V_AUX | NORAML_BUS | BUS | 1 | 5.5 | 5 | 10 | 5 | 12 | 5 | 12 | 12 | 12 | 12 | 12 |  |  |  |
| NCT7904_VSEN1 | NORAML_BUS | BUS | 1 | 5.5 | 5 | 10 | 5 | 12 | 5 | 12 | 12 | 12 | 12 | 12 |  |  |  |
| NCT7904_VSEN10 | NORAML_BUS | BUS | 1 | 5.5 | 5 | 10 | 5 | 12 | 5 | 12 | 12 | 12 | 12 | 12 |  |  |  |
| NCT7904_VSEN11 | NORAML_BUS | BUS | 1 | 5.5 | 5 | 10 | 5 | 12 | 5 | 12 | 12 | 12 | 12 | 12 |  |  |  |
| NCT7904_VSEN12 | NORAML_BUS | BUS | 1 | 5.5 | 5 | 10 | 5 | 12 | 5 | 12 | 12 | 12 | 12 | 12 |  |  |  |
| NCT7904_VSEN13 | NORAML_BUS | BUS | 1 | 5.5 | 5 | 10 | 5 | 12 | 5 | 12 | 12 | 12 | 12 | 12 |  |  |  |
| NCT7904_VSEN14 | NORAML_BUS | BUS | 1 | 5.5 | 5 | 10 | 5 | 12 | 5 | 12 | 12 | 12 | 12 | 12 |  |  |  |
| NCT7904_VSEN6 | NORAML_BUS | BUS | 1 | 5.5 | 5 | 10 | 5 | 12 | 5 | 12 | 12 | 12 | 12 | 12 |  |  |  |
| NCT7904_VSEN7 | NORAML_BUS | BUS | 1 | 5.5 | 5 | 10 | 5 | 12 | 5 | 12 | 12 | 12 | 12 | 12 |  |  |  |
| NCT7904_VSEN8 | NORAML_BUS | BUS | 1 | 5.5 | 5 | 10 | 5 | 12 | 5 | 12 | 12 | 12 | 12 | 12 |  |  |  |
| NCT7904_VSEN9 | NORAML_BUS | BUS | 1 | 5.5 | 5 | 10 | 5 | 12 | 5 | 12 | 12 | 12 | 12 | 12 |  |  |  |
| NCT7904D_PWM1 | NORAML_BUS | BUS | 1 | 5.5 | 5 | 10 | 5 | 12 | 5 | 12 | 12 | 12 | 12 | 12 |  |  |  |
| NCT7904D_PWM2 | NORAML_BUS | BUS | 1 | 5.5 | 5 | 10 | 5 | 12 | 5 | 12 | 12 | 12 | 12 | 12 |  |  |  |
| NCT7904D_PWM3 | NORAML_BUS | BUS | 1 | 5.5 | 5 | 10 | 5 | 12 | 5 | 12 | 12 | 12 | 12 | 12 |  |  |  |
| NCT7904D_PWM4 | NORAML_BUS | BUS | 1 | 5.5 | 5 | 10 | 5 | 12 | 5 | 12 | 12 | 12 | 12 | 12 |  |  |  |
| OSC_TRI_S | NORAML_BUS | BUS | 1 | 5.5 | 5 | 10 | 5 | 12 | 5 | 12 | 12 | 12 | 12 | 12 |  |  |  |
| OTP_RETRY_B | NORAML_BUS | BUS | 1 | 5.5 | 5 | 10 | 5 | 12 | 5 | 12 | 12 | 12 | 12 | 12 |  |  |  |
| OTP_RETRY_C | NORAML_BUS | BUS | 1 | 5.5 | 5 | 10 | 5 | 12 | 5 | 12 | 12 | 12 | 12 | 12 |  |  |  |
| OTP_RETRY_DIODE | NORAML_BUS | BUS | 1 | 5.5 | 5 | 10 | 5 | 12 | 5 | 12 | 12 | 12 | 12 | 12 |  |  |  |
| OTP_RETRY_G | NORAML_BUS | BUS | 1 | 5.5 | 5 | 10 | 5 | 12 | 5 | 12 | 12 | 12 | 12 | 12 |  |  |  |
| P12VL_2490_EN_1 | NORAML_BUS | BUS | 1 | 5.5 | 5 | 10 | 5 | 12 | 5 | 12 | 12 | 12 | 12 | 12 |  |  |  |
| P12VL_2490_EN_2 | NORAML_BUS | BUS | 1 | 5.5 | 5 | 10 | 5 | 12 | 5 | 12 | 12 | 12 | 12 | 12 |  |  |  |
| P12VL_2490_PG | NORAML_BUS | BUS | 1 | 5.5 | 5 | 10 | 5 | 12 | 5 | 12 | 12 | 12 | 12 | 12 |  |  |  |
| P12VU_2490_EN_1 | NORAML_BUS | BUS | 1 | 5.5 | 5 | 10 | 5 | 12 | 5 | 12 | 12 | 12 | 12 | 12 |  |  |  |
| P12VU_2490_EN_2 | NORAML_BUS | BUS | 1 | 5.5 | 5 | 10 | 5 | 12 | 5 | 12 | 12 | 12 | 12 | 12 |  |  |  |
| P12VU_2490_PG | NORAML_BUS | BUS | 1 | 5.5 | 5 | 10 | 5 | 12 | 5 | 12 | 12 | 12 | 12 | 12 |  |  |  |
| PWM_BUFFER_IN_FAN1_FAN2 | NORAML_BUS | BUS | 1 | 5.5 | 5 | 10 | 5 | 12 | 5 | 12 | 12 | 12 | 12 | 12 |  |  |  |
| PWM_BUFFER_IN_FAN3_FAN4 | NORAML_BUS | BUS | 1 | 5.5 | 5 | 10 | 5 | 12 | 5 | 12 | 12 | 12 | 12 | 12 |  |  |  |
| PWM_BUFFER_IN_FAN5_FAN6 | NORAML_BUS | BUS | 1 | 5.5 | 5 | 10 | 5 | 12 | 5 | 12 | 12 | 12 | 12 | 12 |  |  |  |
| PWM_EXP_1A | NORAML_BUS | BUS | 1 | 5.5 | 5 | 10 | 5 | 12 | 5 | 12 | 12 | 12 | 12 | 12 |  |  |  |
| PWM_EXP_1B | NORAML_BUS | BUS | 1 | 5.5 | 5 | 10 | 5 | 12 | 5 | 12 | 12 | 12 | 12 | 12 |  |  |  |
| PWM_EXP_2A | NORAML_BUS | BUS | 1 | 5.5 | 5 | 10 | 5 | 12 | 5 | 12 | 12 | 12 | 12 | 12 |  |  |  |
| PWM_EXP_2B | NORAML_BUS | BUS | 1 | 5.5 | 5 | 10 | 5 | 12 | 5 | 12 | 12 | 12 | 12 | 12 |  |  |  |
| PWM_OUT | NORAML_BUS | BUS | 1 | 5.5 | 5 | 10 | 5 | 12 | 5 | 12 | 12 | 12 | 12 | 12 |  |  |  |
| SD_LATCH_RELEASE_L | NORAML_BUS | BUS | 1 | 5.5 | 5 | 10 | 5 | 12 | 5 | 12 | 12 | 12 | 12 | 12 |  |  |  |
| SD_LATCH_RELEASE_U | NORAML_BUS | BUS | 1 | 5.5 | 5 | 10 | 5 | 12 | 5 | 12 | 12 | 12 | 12 | 12 |  |  |  |
| SEB_PEER_1A_1B_HB_OUT | NORAML_BUS | BUS | 1 | 5.5 | 5 | 10 | 5 | 12 | 5 | 12 | 12 | 12 | 12 | 12 |  |  |  |
| SEB_PEER_1A_HB | NORAML_BUS | BUS | 1 | 5.5 | 5 | 10 | 5 | 12 | 5 | 12 | 12 | 12 | 12 | 12 |  |  |  |
| SEB_PEER_1B_HB | NORAML_BUS | BUS | 1 | 5.5 | 5 | 10 | 5 | 12 | 5 | 12 | 12 | 12 | 12 | 12 |  |  |  |
| SEB_PEER_2A_2B_HB_OUT | NORAML_BUS | BUS | 1 | 5.5 | 5 | 10 | 5 | 12 | 5 | 12 | 12 | 12 | 12 | 12 |  |  |  |
| SEB_PEER_2A_HB | NORAML_BUS | BUS | 1 | 5.5 | 5 | 10 | 5 | 12 | 5 | 12 | 12 | 12 | 12 | 12 |  |  |  |
| SEB_PEER_2B_HB | NORAML_BUS | BUS | 1 | 5.5 | 5 | 10 | 5 | 12 | 5 | 12 | 12 | 12 | 12 | 12 |  |  |  |
| SELF_1A_HB | NORAML_BUS | BUS | 1 | 5.5 | 5 | 10 | 5 | 12 | 5 | 12 | 12 | 12 | 12 | 12 |  |  |  |
| SELF_1B_HB | NORAML_BUS | BUS | 1 | 5.5 | 5 | 10 | 5 | 12 | 5 | 12 | 12 | 12 | 12 | 12 |  |  |  |
| SELF_2A_HB | NORAML_BUS | BUS | 1 | 5.5 | 5 | 10 | 5 | 12 | 5 | 12 | 12 | 12 | 12 | 12 |  |  |  |
| SELF_2B_HB | NORAML_BUS | BUS | 1 | 5.5 | 5 | 10 | 5 | 12 | 5 | 12 | 12 | 12 | 12 | 12 |  |  |  |
| SELF_TRAY_PRESENT_LOWER | NORAML_BUS | BUS | 1 | 5.5 | 5 | 10 | 5 | 12 | 5 | 12 | 12 | 12 | 12 | 12 |  |  |  |
| SELF_TRAY_PRESENT_UPPER | NORAML_BUS | BUS | 1 | 5.5 | 5 | 10 | 5 | 12 | 5 | 12 | 12 | 12 | 12 | 12 |  |  |  |
| TEMP_ALM# | NORAML_BUS | BUS | 1 | 5.5 | 5 | 10 | 5 | 12 | 5 | 12 | 12 | 12 | 12 | 12 |  |  |  |
| TEMP_ALM#_G | NORAML_BUS | BUS | 1 | 5.5 | 5 | 10 | 5 | 12 | 5 | 12 | 12 | 12 | 12 | 12 |  |  |  |
| TEMP_ALM#_IN | NORAML_BUS | BUS | 1 | 5.5 | 5 | 10 | 5 | 12 | 5 | 12 | 12 | 12 | 12 | 12 |  |  |  |
| TEMP_ALM#_IN_D | NORAML_BUS | BUS | 1 | 5.5 | 5 | 10 | 5 | 12 | 5 | 12 | 12 | 12 | 12 | 12 |  |  |  |
| TEMP_ALM#_JP_1 | NORAML_BUS | BUS | 1 | 5.5 | 5 | 10 | 5 | 12 | 5 | 12 | 12 | 12 | 12 | 12 |  |  |  |
| TEMP_ALM#_JP_2 | NORAML_BUS | BUS | 1 | 5.5 | 5 | 10 | 5 | 12 | 5 | 12 | 12 | 12 | 12 | 12 |  |  |  |
| TEMP_ALM#_REVERSE | NORAML_BUS | BUS | 1 | 5.5 | 5 | 10 | 5 | 12 | 5 | 12 | 12 | 12 | 12 | 12 |  |  |  |
| TEMP_ALM#_REVERSE_R | NORAML_BUS | BUS | 1 | 5.5 | 5 | 10 | 5 | 12 | 5 | 12 | 12 | 12 | 12 | 12 |  |  |  |
| THERMHOT# | NORAML_BUS | BUS | 1 | 5.5 | 5 | 10 | 5 | 12 | 5 | 12 | 12 | 12 | 12 | 12 |  |  |  |
| THERMHOT#_R | NORAML_BUS | BUS | 1 | 5.5 | 5 | 10 | 5 | 12 | 5 | 12 | 12 | 12 | 12 | 12 |  |  |  |
| UPPER_TRAY_ID | NORAML_BUS | BUS | 1 | 5.5 | 5 | 10 | 5 | 12 | 5 | 12 | 12 | 12 | 12 | 12 |  |  |  |
| P12V_FAN1 | POWER_BUS_100MIL | BUS | 1 | 100 | 5 | 10 | 5 | 12 | 5 | 12 | 12 | 12 | 12 | 12 |  |  |  |
| P12V_FAN2 | POWER_BUS_100MIL | BUS | 1 | 100 | 5 | 10 | 5 | 12 | 5 | 12 | 12 | 12 | 12 | 12 |  |  |  |
| P12V_FAN3 | POWER_BUS_100MIL | BUS | 1 | 100 | 5 | 10 | 5 | 12 | 5 | 12 | 12 | 12 | 12 | 12 |  |  |  |
| P12V_FAN4 | POWER_BUS_100MIL | BUS | 1 | 100 | 5 | 10 | 5 | 12 | 5 | 12 | 12 | 12 | 12 | 12 |  |  |  |
| P12V_FAN5 | POWER_BUS_100MIL | BUS | 1 | 100 | 5 | 10 | 5 | 12 | 5 | 12 | 12 | 12 | 12 | 12 |  |  |  |
| P12V_FAN6 | POWER_BUS_100MIL | BUS | 1 | 100 | 5 | 10 | 5 | 12 | 5 | 12 | 12 | 12 | 12 | 12 |  |  |  |
| ADM1276_EN | POWER_BUS_10MIL | BUS | 1 | 10 | 5 | 10 | 5 | 12 | 5 | 12 | 12 | 12 | 12 | 12 |  |  |  |
| ADM1276_EN_NET | POWER_BUS_10MIL | BUS | 1 | 10 | 5 | 10 | 5 | 12 | 5 | 12 | 12 | 12 | 12 | 12 |  |  |  |
| ADM1276_LATCH# | POWER_BUS_10MIL | BUS | 1 | 10 | 5 | 10 | 5 | 12 | 5 | 12 | 12 | 12 | 12 | 12 |  |  |  |
| ADM1276_LATCH_B | POWER_BUS_10MIL | BUS | 1 | 10 | 5 | 10 | 5 | 12 | 5 | 12 | 12 | 12 | 12 | 12 |  |  |  |
| ADM1276_OV | POWER_BUS_10MIL | BUS | 1 | 10 | 5 | 10 | 5 | 12 | 5 | 12 | 12 | 12 | 12 | 12 |  |  |  |
| ADM1276_PWRGD | POWER_BUS_10MIL | BUS | 1 | 10 | 5 | 10 | 5 | 12 | 5 | 12 | 12 | 12 | 12 | 12 |  |  |  |
| ADM1276_SENSE- | POWER_BUS_10MIL | BUS | 1 | 10 | 5 | 10 | 5 | 12 | 5 | 12 | 12 | 12 | 12 | 12 |  |  |  |
| ADM1276_SENSE+ | POWER_BUS_10MIL | BUS | 1 | 10 | 5 | 10 | 5 | 12 | 5 | 12 | 12 | 12 | 12 | 12 |  |  |  |
| ADM1276_SS | POWER_BUS_10MIL | BUS | 1 | 10 | 5 | 10 | 5 | 12 | 5 | 12 | 12 | 12 | 12 | 12 |  |  |  |
| ADM1276_TIMER | POWER_BUS_10MIL | BUS | 1 | 10 | 5 | 10 | 5 | 12 | 5 | 12 | 12 | 12 | 12 | 12 |  |  |  |
| ADM1276_UV | POWER_BUS_10MIL | BUS | 1 | 10 | 5 | 10 | 5 | 12 | 5 | 12 | 12 | 12 | 12 | 12 |  |  |  |
| ADM1276_VCC | POWER_BUS_10MIL | BUS | 1 | 10 | 5 | 10 | 5 | 12 | 5 | 12 | 12 | 12 | 12 | 12 |  |  |  |
| P12VL_2490_PROG | POWER_BUS_10MIL | BUS | 1 | 10 | 5 | 10 | 5 | 12 | 5 | 12 | 12 | 12 | 12 | 12 |  |  |  |
| P12VL_2490_TIMER | POWER_BUS_10MIL | BUS | 1 | 10 | 5 | 10 | 5 | 12 | 5 | 12 | 12 | 12 | 12 | 12 |  |  |  |
| P12VL_2490_VREF | POWER_BUS_10MIL | BUS | 1 | 10 | 5 | 10 | 5 | 12 | 5 | 12 | 12 | 12 | 12 | 12 |  |  |  |
| P12VU_2490_PROG | POWER_BUS_10MIL | BUS | 1 | 10 | 5 | 10 | 5 | 12 | 5 | 12 | 12 | 12 | 12 | 12 |  |  |  |
| P12VU_2490_TIMER | POWER_BUS_10MIL | BUS | 1 | 10 | 5 | 10 | 5 | 12 | 5 | 12 | 12 | 12 | 12 | 12 |  |  |  |
| P12VU_2490_VREF | POWER_BUS_10MIL | BUS | 1 | 10 | 5 | 10 | 5 | 12 | 5 | 12 | 12 | 12 | 12 | 12 |  |  |  |
| P3V3_BS_NET | POWER_BUS_10MIL | BUS | 1 | 10 | 5 | 10 | 5 | 12 | 5 | 12 | 12 | 12 | 12 | 12 |  |  |  |
| P3V3_EN | POWER_BUS_10MIL | BUS | 1 | 10 | 5 | 10 | 5 | 12 | 5 | 12 | 12 | 12 | 12 | 12 |  |  |  |
| P3V3_FB | POWER_BUS_10MIL | BUS | 1 | 10 | 5 | 10 | 5 | 12 | 5 | 12 | 12 | 12 | 12 | 12 |  |  |  |
| PWM_OUT_FAN1 | POWER_BUS_10MIL | BUS | 1 | 10 | 5 | 10 | 5 | 12 | 5 | 12 | 12 | 12 | 12 | 12 |  |  |  |
| PWM_OUT_FAN1_NET | POWER_BUS_10MIL | BUS | 1 | 10 | 5 | 10 | 5 | 12 | 5 | 12 | 12 | 12 | 12 | 12 |  |  |  |
| PWM_OUT_FAN2 | POWER_BUS_10MIL | BUS | 1 | 10 | 5 | 10 | 5 | 12 | 5 | 12 | 12 | 12 | 12 | 12 |  |  |  |
| PWM_OUT_FAN2_NET | POWER_BUS_10MIL | BUS | 1 | 10 | 5 | 10 | 5 | 12 | 5 | 12 | 12 | 12 | 12 | 12 |  |  |  |
| PWM_OUT_FAN3 | POWER_BUS_10MIL | BUS | 1 | 10 | 5 | 10 | 5 | 12 | 5 | 12 | 12 | 12 | 12 | 12 |  |  |  |
| PWM_OUT_FAN3_NET | POWER_BUS_10MIL | BUS | 1 | 10 | 5 | 10 | 5 | 12 | 5 | 12 | 12 | 12 | 12 | 12 |  |  |  |
| PWM_OUT_FAN4 | POWER_BUS_10MIL | BUS | 1 | 10 | 5 | 10 | 5 | 12 | 5 | 12 | 12 | 12 | 12 | 12 |  |  |  |
| PWM_OUT_FAN4_NET | POWER_BUS_10MIL | BUS | 1 | 10 | 5 | 10 | 5 | 12 | 5 | 12 | 12 | 12 | 12 | 12 |  |  |  |
| PWM_OUT_FAN5 | POWER_BUS_10MIL | BUS | 1 | 10 | 5 | 10 | 5 | 12 | 5 | 12 | 12 | 12 | 12 | 12 |  |  |  |
| PWM_OUT_FAN5_NET | POWER_BUS_10MIL | BUS | 1 | 10 | 5 | 10 | 5 | 12 | 5 | 12 | 12 | 12 | 12 | 12 |  |  |  |
| PWM_OUT_FAN6 | POWER_BUS_10MIL | BUS | 1 | 10 | 5 | 10 | 5 | 12 | 5 | 12 | 12 | 12 | 12 | 12 |  |  |  |
| PWM_OUT_FAN6_NET | POWER_BUS_10MIL | BUS | 1 | 10 | 5 | 10 | 5 | 12 | 5 | 12 | 12 | 12 | 12 | 12 |  |  |  |
| SENSE-_R1 | POWER_BUS_10MIL | BUS | 1 | 10 | 5 | 10 | 5 | 12 | 5 | 12 | 12 | 12 | 12 | 12 |  |  |  |
| SENSE-_R2 | POWER_BUS_10MIL | BUS | 1 | 10 | 5 | 10 | 5 | 12 | 5 | 12 | 12 | 12 | 12 | 12 |  |  |  |
| SENSE-_R3 | POWER_BUS_10MIL | BUS | 1 | 10 | 5 | 10 | 5 | 12 | 5 | 12 | 12 | 12 | 12 | 12 |  |  |  |
| SENSE-_R4 | POWER_BUS_10MIL | BUS | 1 | 10 | 5 | 10 | 5 | 12 | 5 | 12 | 12 | 12 | 12 | 12 |  |  |  |
| SENSE+_R1 | POWER_BUS_10MIL | BUS | 1 | 10 | 5 | 10 | 5 | 12 | 5 | 12 | 12 | 12 | 12 | 12 |  |  |  |
| SENSE+_R2 | POWER_BUS_10MIL | BUS | 1 | 10 | 5 | 10 | 5 | 12 | 5 | 12 | 12 | 12 | 12 | 12 |  |  |  |
| SENSE+_R3 | POWER_BUS_10MIL | BUS | 1 | 10 | 5 | 10 | 5 | 12 | 5 | 12 | 12 | 12 | 12 | 12 |  |  |  |
| SENSE+_R4 | POWER_BUS_10MIL | BUS | 1 | 10 | 5 | 10 | 5 | 12 | 5 | 12 | 12 | 12 | 12 | 12 |  |  |  |
| ADM1276_VOUT | POWER_BUS_1600MIL | BUS | 1 | 1600 | 5 | 10 | 5 | 12 | 5 | 12 | 12 | 12 | 12 | 12 |  |  |  |
| GND | POWER_BUS_1600MIL | BUS | 1 | 1600 | 5 | 10 | 5 | 12 | 5 | 12 | 12 | 12 | 12 | 12 |  |  |  |
| P12V | POWER_BUS_1600MIL | BUS | 1 | 1600 | 5 | 10 | 5 | 12 | 5 | 12 | 12 | 12 | 12 | 12 |  |  |  |
| P12V_AUX | POWER_BUS_1600MIL | BUS | 1 | 1600 | 5 | 10 | 5 | 12 | 5 | 12 | 12 | 12 | 12 | 12 |  |  |  |
| P12V_SENSE_TRACE | POWER_BUS_1600MIL | BUS | 1 | 1600 | 5 | 10 | 5 | 12 | 5 | 12 | 12 | 12 | 12 | 12 |  |  |  |
| ADM1276_VCAP | POWER_BUS_20MIL | BUS | 1 | 20 | 5 | 10 | 5 | 12 | 5 | 12 | 12 | 12 | 12 | 12 |  |  |  |
| P12VL_2490_GATE | POWER_BUS_20MIL | BUS | 1 | 20 | 5 | 10 | 5 | 12 | 5 | 12 | 12 | 12 | 12 | 12 |  |  |  |
| P12VL_2490_GATE_DRV | POWER_BUS_20MIL | BUS | 1 | 20 | 5 | 10 | 5 | 12 | 5 | 12 | 12 | 12 | 12 | 12 |  |  |  |
| P12VL_2490_GATE_DRV_2 | POWER_BUS_20MIL | BUS | 1 | 20 | 5 | 10 | 5 | 12 | 5 | 12 | 12 | 12 | 12 | 12 |  |  |  |
| P12VL_2490_RC | POWER_BUS_20MIL | BUS | 1 | 20 | 5 | 10 | 5 | 12 | 5 | 12 | 12 | 12 | 12 | 12 |  |  |  |
| P12VL_2490_SENSE | POWER_BUS_20MIL | BUS | 1 | 20 | 5 | 10 | 5 | 12 | 5 | 12 | 12 | 12 | 12 | 12 |  |  |  |
| P12VL_2490_VCC | POWER_BUS_20MIL | BUS | 1 | 20 | 5 | 10 | 5 | 12 | 5 | 12 | 12 | 12 | 12 | 12 |  |  |  |
| P12VU_2490_GATE | POWER_BUS_20MIL | BUS | 1 | 20 | 5 | 10 | 5 | 12 | 5 | 12 | 12 | 12 | 12 | 12 |  |  |  |
| P12VU_2490_GATE_DRV | POWER_BUS_20MIL | BUS | 1 | 20 | 5 | 10 | 5 | 12 | 5 | 12 | 12 | 12 | 12 | 12 |  |  |  |
| P12VU_2490_GATE_DRV_2 | POWER_BUS_20MIL | BUS | 1 | 20 | 5 | 10 | 5 | 12 | 5 | 12 | 12 | 12 | 12 | 12 |  |  |  |
| P12VU_2490_RC | POWER_BUS_20MIL | BUS | 1 | 20 | 5 | 10 | 5 | 12 | 5 | 12 | 12 | 12 | 12 | 12 |  |  |  |
| P12VU_2490_SENSE | POWER_BUS_20MIL | BUS | 1 | 20 | 5 | 10 | 5 | 12 | 5 | 12 | 12 | 12 | 12 | 12 |  |  |  |
| P12VU_2490_VCC | POWER_BUS_20MIL | BUS | 1 | 20 | 5 | 10 | 5 | 12 | 5 | 12 | 12 | 12 | 12 | 12 |  |  |  |
| P12VL | POWER_BUS_400MIL | BUS | 1 | 400 | 5 | 10 | 5 | 12 | 5 | 12 | 12 | 12 | 12 | 12 |  |  |  |
| P12VL_NET | POWER_BUS_400MIL | BUS | 1 | 400 | 5 | 10 | 5 | 12 | 5 | 12 | 12 | 12 | 12 | 12 |  |  |  |
| P12VU | POWER_BUS_400MIL | BUS | 1 | 400 | 5 | 10 | 5 | 12 | 5 | 12 | 12 | 12 | 12 | 12 |  |  |  |
| P12VU_NET | POWER_BUS_400MIL | BUS | 1 | 400 | 5 | 10 | 5 | 12 | 5 | 12 | 12 | 12 | 12 | 12 |  |  |  |
| ADM1276_FLB | POWER_BUS_40MIL | BUS | 1 | 40 | 5 | 10 | 5 | 12 | 5 | 12 | 12 | 12 | 12 | 12 |  |  |  |
| ADM1276_GATE | POWER_BUS_40MIL | BUS | 1 | 40 | 5 | 10 | 5 | 12 | 5 | 12 | 12 | 12 | 12 | 12 |  |  |  |
| ADM1276_GATE_DRV | POWER_BUS_40MIL | BUS | 1 | 40 | 5 | 10 | 5 | 12 | 5 | 12 | 12 | 12 | 12 | 12 |  |  |  |
| ADM1276_GATE_DRV0 | POWER_BUS_40MIL | BUS | 1 | 40 | 5 | 10 | 5 | 12 | 5 | 12 | 12 | 12 | 12 | 12 |  |  |  |
| ADM1276_GATE_DRV1 | POWER_BUS_40MIL | BUS | 1 | 40 | 5 | 10 | 5 | 12 | 5 | 12 | 12 | 12 | 12 | 12 |  |  |  |
| ADM1276_GATE_DRV2 | POWER_BUS_40MIL | BUS | 1 | 40 | 5 | 10 | 5 | 12 | 5 | 12 | 12 | 12 | 12 | 12 |  |  |  |
| ADM1276_GATE_DRV3 | POWER_BUS_40MIL | BUS | 1 | 40 | 5 | 10 | 5 | 12 | 5 | 12 | 12 | 12 | 12 | 12 |  |  |  |
| ADM1276_GATE_RC | POWER_BUS_40MIL | BUS | 1 | 40 | 5 | 10 | 5 | 12 | 5 | 12 | 12 | 12 | 12 | 12 |  |  |  |
| ADM1276_GATE_RSV | POWER_BUS_40MIL | BUS | 1 | 40 | 5 | 10 | 5 | 12 | 5 | 12 | 12 | 12 | 12 | 12 |  |  |  |
| ADM1276_ISET | POWER_BUS_40MIL | BUS | 1 | 40 | 5 | 10 | 5 | 12 | 5 | 12 | 12 | 12 | 12 | 12 |  |  |  |
| P3V3 | POWER_BUS_40MIL | BUS | 1 | 40 | 5 | 10 | 5 | 12 | 5 | 12 | 12 | 12 | 12 | 12 |  |  |  |
| P3V3_AUX | POWER_BUS_40MIL | BUS | 1 | 40 | 5 | 10 | 5 | 12 | 5 | 12 | 12 | 12 | 12 | 12 |  |  |  |
| P3V3_AUX_BJT_B | POWER_BUS_40MIL | BUS | 1 | 40 | 5 | 10 | 5 | 12 | 5 | 12 | 12 | 12 | 12 | 12 |  |  |  |
| P3V3_IN | POWER_BUS_40MIL | BUS | 1 | 40 | 5 | 10 | 5 | 12 | 5 | 12 | 12 | 12 | 12 | 12 |  |  |  |
| P3V3_LX | POWER_BUS_40MIL | BUS | 1 | 40 | 5 | 10 | 5 | 12 | 5 | 12 | 12 | 12 | 12 | 12 |  |  |  |
| P3V3_LX_COPPER | POWER_BUS_40MIL | BUS | 1 | 40 | 5 | 10 | 5 | 12 | 5 | 12 | 12 | 12 | 12 | 12 |  |  |  |
| P3V3_LX_REV | POWER_BUS_40MIL | BUS | 1 | 40 | 5 | 10 | 5 | 12 | 5 | 12 | 12 | 12 | 12 | 12 |  |  |  |
